(kicad_pcb
	(version 20260206)
	(generator "pcbnew")
	(generator_version "10.0")
	(general
		(thickness 1.6)
		(legacy_teardrops no)
	)
	(paper "A4")
	(title_block
		(title "Wiwynn_Tioga_Pass_MB.brd")
		(comment 1 "Tioga Pass / footprints 3960-3966 of 4770")
	)
	(layers
		(0 "F.Cu" signal "TOP")
		(4 "In1.Cu" signal "L2GND")
		(6 "In2.Cu" signal "L3")
		(8 "In3.Cu" signal "L4GND")
		(10 "In4.Cu" signal "L5")
		(12 "In5.Cu" signal "L6GND")
		(14 "In6.Cu" signal "L7VCC")
		(16 "In7.Cu" signal "L8VCC")
		(18 "In8.Cu" signal "L9GND")
		(20 "In9.Cu" signal "L10")
		(22 "In10.Cu" signal "L11GND")
		(24 "In11.Cu" signal "L12")
		(26 "In12.Cu" signal "L13GND")
		(2 "B.Cu" signal "BOTTOM")
		(9 "F.Adhes" user "F.Adhesive")
		(11 "B.Adhes" user "B.Adhesive")
		(13 "F.Paste" user "Package Geometry/Pastemask Top")
		(15 "B.Paste" user "Package Geometry/Pastemask Bottom")
		(5 "F.SilkS" user "Ref Des/Silkscreen Top")
		(7 "B.SilkS" user "Ref Des/Silkscreen Bottom")
		(1 "F.Mask" user "Board Geometry/Soldermask Top")
		(3 "B.Mask" user "Board Geometry/Soldermask Bottom")
		(17 "Dwgs.User" user "User.Drawings")
		(19 "Cmts.User" user "User.Comments")
		(21 "Eco1.User" user "User.Eco1")
		(23 "Eco2.User" user "User.Eco2")
		(25 "Edge.Cuts" user "Board Geometry/Outline")
		(27 "Margin" user)
		(31 "F.CrtYd" user "Package Geometry/Place Bound Top")
		(29 "B.CrtYd" user "Package Geometry/Place Bound Bottom")
		(35 "F.Fab" user "Ref Des/Assembly Top")
		(33 "B.Fab" user "Ref Des/Assembly Bottom")
	)
	(footprint ""
		(layer "B.Cu")
		(at 28.547568 -144.4752 180)
		(property "Reference" "R9L7"
			(at 0 0 0)
			(layer "B.SilkS")
			(hide yes)
			(effects
				(font
					(size 1.27 1.27)
				)
				(justify mirror)
			)
		)
		(property "Value" ""
			(at 0 0 0)
			(layer "B.Fab")
			(effects
				(font
					(size 1.27 1.27)
				)
				(justify mirror)
			)
		)
		(duplicate_pad_numbers_are_jumpers no)
		(fp_poly
			(pts
				(xy 0.2794 -0.1016) (xy -0.2794 -0.1016) (xy -0.2794 0.9906) (xy 0.2794 0.9906)
			)
			(stroke
				(width 0)
				(type default)
			)
			(fill no)
			(layer "B.CrtYd")
		)
		(fp_line
			(start 0.2794 0.9906)
			(end -0.2794 0.9906)
			(stroke
				(width 0.1)
				(type default)
			)
			(layer "B.Fab")
		)
		(fp_line
			(start 0.2794 -0.1016)
			(end 0.2794 0.9906)
			(stroke
				(width 0.1)
				(type default)
			)
			(layer "B.Fab")
		)
		(fp_line
			(start -0.2794 0.9906)
			(end -0.2794 -0.1016)
			(stroke
				(width 0.1)
				(type default)
			)
			(layer "B.Fab")
		)
		(fp_line
			(start -0.2794 -0.1016)
			(end 0.2794 -0.1016)
			(stroke
				(width 0.1)
				(type default)
			)
			(layer "B.Fab")
		)
		(pad "1" smd rect
			(at 0 0)
			(size 0.508 0.508)
			(layers "B.Cu" "B.Mask" "B.Paste")
			(net "PVDDQ_KLM")
		)
		(pad "2" smd rect
			(at 0 0.889)
			(size 0.508 0.508)
			(layers "B.Cu" "B.Mask" "B.Paste")
			(net "M_L_VREF")
		)
		(zone
			(layer "B.Cu")
			(hatch none 0.5)
			(connect_pads
				(clearance 0)
			)
			(min_thickness 0.25)
			(keepout
				(tracks not_allowed)
				(vias allowed)
				(pads allowed)
				(copperpour not_allowed)
				(footprints allowed)
			)
			(placement
				(enabled no)
				(sheetname "")
			)
			(fill
				(thermal_gap 0.5)
				(thermal_bridge_width 0.5)
				(island_removal_mode 0)
			)
			(polygon
				(pts
					(xy 28.293568 -145.1102) (xy 28.801568 -145.1102) (xy 28.801568 -144.7292) (xy 28.293568 -144.7292)
				)
			)
		)
		(zone
			(layer "B.Cu")
			(hatch none 0.5)
			(connect_pads
				(clearance 0)
			)
			(min_thickness 0.25)
			(keepout
				(tracks allowed)
				(vias not_allowed)
				(pads allowed)
				(copperpour not_allowed)
				(footprints allowed)
			)
			(placement
				(enabled no)
				(sheetname "")
			)
			(fill
				(thermal_gap 0.5)
				(thermal_bridge_width 0.5)
				(island_removal_mode 0)
			)
			(polygon
				(pts
					(xy 28.293568 -144.7292) (xy 28.801568 -144.7292) (xy 28.801568 -145.1102) (xy 28.293568 -145.1102)
				)
			)
		)
	)
	(footprint ""
		(layer "B.Cu")
		(at 92.85986 -149.77872 -90)
		(property "Reference" "C5G97"
			(at -1.14681 0.76708 0)
			(unlocked yes)
			(layer "B.SilkS")
			(effects
				(font
					(size 0.7874 0.5842)
					(thickness 0.1524)
				)
				(justify mirror)
			)
		)
		(property "Value" ""
			(at 0 0 90)
			(layer "B.Fab")
			(effects
				(font
					(size 1.27 1.27)
				)
				(justify mirror)
			)
		)
		(duplicate_pad_numbers_are_jumpers no)
		(fp_rect
			(start -0.4953 -0.2032)
			(end 0.4953 1.6002)
			(stroke
				(width 0)
				(type default)
			)
			(fill no)
			(layer "B.CrtYd")
		)
		(fp_line
			(start -0.4953 1.6002)
			(end 0.4953 1.6002)
			(stroke
				(width 0.1)
				(type default)
			)
			(layer "B.Fab")
		)
		(fp_line
			(start 0.4953 1.6002)
			(end 0.4953 -0.2032)
			(stroke
				(width 0.1)
				(type default)
			)
			(layer "B.Fab")
		)
		(fp_line
			(start -0.4953 -0.2032)
			(end -0.4953 1.6002)
			(stroke
				(width 0.1)
				(type default)
			)
			(layer "B.Fab")
		)
		(fp_line
			(start 0.4953 -0.2032)
			(end -0.4953 -0.2032)
			(stroke
				(width 0.1)
				(type default)
			)
			(layer "B.Fab")
		)
		(pad "1" smd rect
			(at 0 0 90)
			(size 0.762 0.889)
			(layers "B.Cu" "B.Mask" "B.Paste")
			(net "PVDDQ_KLM")
		)
		(pad "2" smd rect
			(at 0 1.397 90)
			(size 0.762 0.889)
			(layers "B.Cu" "B.Mask" "B.Paste")
			(net "GND")
		)
		(zone
			(layer "B.Cu")
			(hatch none 0.5)
			(connect_pads
				(clearance 0)
			)
			(min_thickness 0.25)
			(keepout
				(tracks not_allowed)
				(vias allowed)
				(pads allowed)
				(copperpour not_allowed)
				(footprints allowed)
			)
			(placement
				(enabled no)
				(sheetname "")
			)
			(fill
				(thermal_gap 0.5)
				(thermal_bridge_width 0.5)
				(island_removal_mode 0)
			)
			(polygon
				(pts
					(xy 92.41536 -150.15972) (xy 91.90736 -150.15972) (xy 91.90736 -149.39772) (xy 92.41536 -149.39772)
				)
			)
		)
	)
	(footprint ""
		(layer "B.Cu")
		(at 372.609618 -88.89111 180)
		(property "Reference" "R7C11"
			(at 0 0 0)
			(layer "B.SilkS")
			(hide yes)
			(effects
				(font
					(size 1.27 1.27)
				)
				(justify mirror)
			)
		)
		(property "Value" ""
			(at 0 0 0)
			(layer "B.Fab")
			(effects
				(font
					(size 1.27 1.27)
				)
				(justify mirror)
			)
		)
		(duplicate_pad_numbers_are_jumpers no)
		(fp_poly
			(pts
				(xy 0.2794 -0.1016) (xy -0.2794 -0.1016) (xy -0.2794 0.9906) (xy 0.2794 0.9906)
			)
			(stroke
				(width 0)
				(type default)
			)
			(fill no)
			(layer "B.CrtYd")
		)
		(fp_line
			(start 0.2794 0.9906)
			(end -0.2794 0.9906)
			(stroke
				(width 0.1)
				(type default)
			)
			(layer "B.Fab")
		)
		(fp_line
			(start 0.2794 -0.1016)
			(end 0.2794 0.9906)
			(stroke
				(width 0.1)
				(type default)
			)
			(layer "B.Fab")
		)
		(fp_line
			(start -0.2794 0.9906)
			(end -0.2794 -0.1016)
			(stroke
				(width 0.1)
				(type default)
			)
			(layer "B.Fab")
		)
		(fp_line
			(start -0.2794 -0.1016)
			(end 0.2794 -0.1016)
			(stroke
				(width 0.1)
				(type default)
			)
			(layer "B.Fab")
		)
		(pad "1" smd rect
			(at 0 0)
			(size 0.508 0.508)
			(layers "B.Cu" "B.Mask" "B.Paste")
			(net "GND")
		)
		(pad "2" smd rect
			(at 0 0.889)
			(size 0.508 0.508)
			(layers "B.Cu" "B.Mask" "B.Paste")
			(net "RST_RTCRST_N")
		)
		(zone
			(layer "B.Cu")
			(hatch none 0.5)
			(connect_pads
				(clearance 0)
			)
			(min_thickness 0.25)
			(keepout
				(tracks not_allowed)
				(vias allowed)
				(pads allowed)
				(copperpour not_allowed)
				(footprints allowed)
			)
			(placement
				(enabled no)
				(sheetname "")
			)
			(fill
				(thermal_gap 0.5)
				(thermal_bridge_width 0.5)
				(island_removal_mode 0)
			)
			(polygon
				(pts
					(xy 372.355618 -89.52611) (xy 372.863618 -89.52611) (xy 372.863618 -89.14511) (xy 372.355618 -89.14511)
				)
			)
		)
		(zone
			(layer "B.Cu")
			(hatch none 0.5)
			(connect_pads
				(clearance 0)
			)
			(min_thickness 0.25)
			(keepout
				(tracks allowed)
				(vias not_allowed)
				(pads allowed)
				(copperpour not_allowed)
				(footprints allowed)
			)
			(placement
				(enabled no)
				(sheetname "")
			)
			(fill
				(thermal_gap 0.5)
				(thermal_bridge_width 0.5)
				(island_removal_mode 0)
			)
			(polygon
				(pts
					(xy 372.355618 -89.14511) (xy 372.863618 -89.14511) (xy 372.863618 -89.52611) (xy 372.355618 -89.52611)
				)
			)
		)
	)
	(footprint ""
		(layer "B.Cu")
		(at 16.0782 -84.455 90)
		(property "Reference" "Q9P1"
			(at -2.286 -1.37287 270)
			(unlocked yes)
			(layer "B.SilkS")
			(effects
				(font
					(size 0.7874 0.5842)
					(thickness 0.1524)
				)
				(justify left mirror)
			)
		)
		(property "Value" ""
			(at 0 0 90)
			(layer "B.Fab")
			(effects
				(font
					(size 1.27 1.27)
				)
				(justify mirror)
			)
		)
		(duplicate_pad_numbers_are_jumpers no)
		(fp_circle
			(center 0.848614 -0.6477)
			(end 0.848614 -0.5207)
			(stroke
				(width 0.254)
				(type default)
			)
			(fill no)
			(layer "B.SilkS")
		)
		(fp_poly
			(pts
				(xy -0.21463 -0.450088) (xy -1.56337 -0.450088) (xy -1.56337 1.75006) (xy -0.21463 1.75006)
			)
			(stroke
				(width 0)
				(type default)
			)
			(fill no)
			(layer "B.CrtYd")
		)
		(fp_line
			(start -0.21463 -0.450088)
			(end -1.56337 -0.450088)
			(stroke
				(width 0.1)
				(type default)
			)
			(layer "B.Fab")
		)
		(fp_line
			(start -1.56337 -0.450088)
			(end -1.56337 1.75006)
			(stroke
				(width 0.1)
				(type default)
			)
			(layer "B.Fab")
		)
		(fp_line
			(start -0.21463 1.75006)
			(end -0.21463 -0.450088)
			(stroke
				(width 0.1)
				(type default)
			)
			(layer "B.Fab")
		)
		(fp_line
			(start -1.56337 1.75006)
			(end -0.21463 1.75006)
			(stroke
				(width 0.1)
				(type default)
			)
			(layer "B.Fab")
		)
		(fp_circle
			(center 0.848614 -0.6477)
			(end 0.848614 -0.5207)
			(stroke
				(width 0.254)
				(type default)
			)
			(fill no)
			(layer "B.Fab")
		)
		(pad "1" smd rect
			(at 0 0 270)
			(size 1.016 0.381)
			(layers "B.Cu" "B.Mask" "B.Paste")
			(net "GND")
		)
		(pad "2" smd rect
			(at 0 0.649986 270)
			(size 1.016 0.381)
			(layers "B.Cu" "B.Mask" "B.Paste")
			(net "A_HSC_LOW_GATE")
		)
		(pad "3" smd rect
			(at 0 1.299972 270)
			(size 1.016 0.381)
			(layers "B.Cu" "B.Mask" "B.Paste")
			(net "IRQ_UV_DETECT_N")
		)
		(pad "4" smd rect
			(at -1.778 1.299972 270)
			(size 1.016 0.381)
			(layers "B.Cu" "B.Mask" "B.Paste")
			(net "GND")
		)
		(pad "5" smd rect
			(at -1.778 0.649986 270)
			(size 1.016 0.381)
			(layers "B.Cu" "B.Mask" "B.Paste")
			(net "A_P12V_STBY_FPH_GATE")
		)
		(pad "6" smd rect
			(at -1.778 0 270)
			(size 1.016 0.381)
			(layers "B.Cu" "B.Mask" "B.Paste")
			(net "A_HSC_LOW_DRAIN")
		)
	)
	(footprint ""
		(layer "B.Cu")
		(at 450.5325 -25.273 -90)
		(property "Reference" "R6W23"
			(at 0.8382 -0.67818 270)
			(unlocked yes)
			(layer "B.SilkS")
			(effects
				(font
					(size 0.4064 0.254)
					(thickness 0.1524)
				)
				(justify left mirror)
			)
		)
		(property "Value" ""
			(at 0 0 90)
			(layer "B.Fab")
			(effects
				(font
					(size 1.27 1.27)
				)
				(justify mirror)
			)
		)
		(duplicate_pad_numbers_are_jumpers no)
		(fp_poly
			(pts
				(xy 0.2794 -0.1016) (xy -0.2794 -0.1016) (xy -0.2794 0.9906) (xy 0.2794 0.9906)
			)
			(stroke
				(width 0)
				(type default)
			)
			(fill no)
			(layer "B.CrtYd")
		)
		(fp_line
			(start -0.2794 0.9906)
			(end -0.2794 -0.1016)
			(stroke
				(width 0.1)
				(type default)
			)
			(layer "B.Fab")
		)
		(fp_line
			(start 0.2794 0.9906)
			(end -0.2794 0.9906)
			(stroke
				(width 0.1)
				(type default)
			)
			(layer "B.Fab")
		)
		(fp_line
			(start -0.2794 -0.1016)
			(end 0.2794 -0.1016)
			(stroke
				(width 0.1)
				(type default)
			)
			(layer "B.Fab")
		)
		(fp_line
			(start 0.2794 -0.1016)
			(end 0.2794 0.9906)
			(stroke
				(width 0.1)
				(type default)
			)
			(layer "B.Fab")
		)
		(pad "1" smd rect
			(at 0 0 90)
			(size 0.508 0.508)
			(layers "B.Cu" "B.Mask" "B.Paste")
			(net "PD_ID_EEPROM_WP")
		)
		(pad "2" smd rect
			(at 0 0.889 90)
			(size 0.508 0.508)
			(layers "B.Cu" "B.Mask" "B.Paste")
			(net "GND")
		)
		(zone
			(layer "B.Cu")
			(hatch none 0.5)
			(connect_pads
				(clearance 0)
			)
			(min_thickness 0.25)
			(keepout
				(tracks not_allowed)
				(vias allowed)
				(pads allowed)
				(copperpour not_allowed)
				(footprints allowed)
			)
			(placement
				(enabled no)
				(sheetname "")
			)
			(fill
				(thermal_gap 0.5)
				(thermal_bridge_width 0.5)
				(island_removal_mode 0)
			)
			(polygon
				(pts
					(xy 449.8975 -25.019) (xy 449.8975 -25.527) (xy 450.2785 -25.527) (xy 450.2785 -25.019)
				)
			)
		)
		(zone
			(layer "B.Cu")
			(hatch none 0.5)
			(connect_pads
				(clearance 0)
			)
			(min_thickness 0.25)
			(keepout
				(tracks allowed)
				(vias not_allowed)
				(pads allowed)
				(copperpour not_allowed)
				(footprints allowed)
			)
			(placement
				(enabled no)
				(sheetname "")
			)
			(fill
				(thermal_gap 0.5)
				(thermal_bridge_width 0.5)
				(island_removal_mode 0)
			)
			(polygon
				(pts
					(xy 450.2785 -25.019) (xy 450.2785 -25.527) (xy 449.8975 -25.527) (xy 449.8975 -25.019)
				)
			)
		)
	)
	(footprint ""
		(layer "B.Cu")
		(at 420.624 -23.114 180)
		(property "Reference" "C25W76"
			(at 0.8382 -0.67818 180)
			(unlocked yes)
			(layer "B.SilkS")
			(effects
				(font
					(size 0.4064 0.254)
					(thickness 0.1524)
				)
				(justify left mirror)
			)
		)
		(property "Value" ""
			(at 0 0 0)
			(layer "B.Fab")
			(effects
				(font
					(size 1.27 1.27)
				)
				(justify mirror)
			)
		)
		(duplicate_pad_numbers_are_jumpers no)
		(fp_poly
			(pts
				(xy -0.3048 -0.1016) (xy -0.3048 0.9906) (xy 0.3048 0.9906) (xy 0.3048 -0.1016)
			)
			(stroke
				(width 0)
				(type default)
			)
			(fill no)
			(layer "B.CrtYd")
		)
		(fp_line
			(start 0.3048 0.9906)
			(end -0.3048 0.9906)
			(stroke
				(width 0.1)
				(type default)
			)
			(layer "B.Fab")
		)
		(fp_line
			(start 0.3048 -0.1016)
			(end 0.3048 0.9906)
			(stroke
				(width 0.1)
				(type default)
			)
			(layer "B.Fab")
		)
		(fp_line
			(start -0.3048 0.9906)
			(end -0.3048 -0.1016)
			(stroke
				(width 0.1)
				(type default)
			)
			(layer "B.Fab")
		)
		(fp_line
			(start -0.3048 -0.1016)
			(end 0.3048 -0.1016)
			(stroke
				(width 0.1)
				(type default)
			)
			(layer "B.Fab")
		)
		(pad "1" smd rect
			(at 0 0)
			(size 0.508 0.508)
			(layers "B.Cu" "B.Mask" "B.Paste")
			(net "V_IO_G_J")
		)
		(pad "2" smd rect
			(at 0 0.889)
			(size 0.508 0.508)
			(layers "B.Cu" "B.Mask" "B.Paste")
			(net "GND")
		)
		(zone
			(layer "B.Cu")
			(hatch none 0.5)
			(connect_pads
				(clearance 0)
			)
			(min_thickness 0.25)
			(keepout
				(tracks not_allowed)
				(vias allowed)
				(pads allowed)
				(copperpour not_allowed)
				(footprints allowed)
			)
			(placement
				(enabled no)
				(sheetname "")
			)
			(fill
				(thermal_gap 0.5)
				(thermal_bridge_width 0.5)
				(island_removal_mode 0)
			)
			(polygon
				(pts
					(xy 420.37 -23.749) (xy 420.878 -23.749) (xy 420.878 -23.368) (xy 420.37 -23.368)
				)
			)
		)
		(zone
			(layer "B.Cu")
			(hatch none 0.5)
			(connect_pads
				(clearance 0)
			)
			(min_thickness 0.25)
			(keepout
				(tracks allowed)
				(vias not_allowed)
				(pads allowed)
				(copperpour not_allowed)
				(footprints allowed)
			)
			(placement
				(enabled no)
				(sheetname "")
			)
			(fill
				(thermal_gap 0.5)
				(thermal_bridge_width 0.5)
				(island_removal_mode 0)
			)
			(polygon
				(pts
					(xy 420.37 -23.368) (xy 420.878 -23.368) (xy 420.878 -23.749) (xy 420.37 -23.749)
				)
			)
		)
	)
	(footprint ""
		(layer "B.Cu")
		(at 14.224 -76.1238)
		(property "Reference" "R9P23"
			(at 0 0 0)
			(layer "B.SilkS")
			(hide yes)
			(effects
				(font
					(size 1.27 1.27)
				)
				(justify mirror)
			)
		)
		(property "Value" ""
			(at 0 0 0)
			(layer "B.Fab")
			(effects
				(font
					(size 1.27 1.27)
				)
				(justify mirror)
			)
		)
		(duplicate_pad_numbers_are_jumpers no)
		(fp_poly
			(pts
				(xy 0.2794 -0.1016) (xy -0.2794 -0.1016) (xy -0.2794 0.9906) (xy 0.2794 0.9906)
			)
			(stroke
				(width 0)
				(type default)
			)
			(fill no)
			(layer "B.CrtYd")
		)
		(fp_line
			(start -0.2794 -0.1016)
			(end 0.2794 -0.1016)
			(stroke
				(width 0.1)
				(type default)
			)
			(layer "B.Fab")
		)
		(fp_line
			(start -0.2794 0.9906)
			(end -0.2794 -0.1016)
			(stroke
				(width 0.1)
				(type default)
			)
			(layer "B.Fab")
		)
		(fp_line
			(start 0.2794 -0.1016)
			(end 0.2794 0.9906)
			(stroke
				(width 0.1)
				(type default)
			)
			(layer "B.Fab")
		)
		(fp_line
			(start 0.2794 0.9906)
			(end -0.2794 0.9906)
			(stroke
				(width 0.1)
				(type default)
			)
			(layer "B.Fab")
		)
		(pad "1" smd rect
			(at 0 0 180)
			(size 0.508 0.508)
			(layers "B.Cu" "B.Mask" "B.Paste")
			(net "P12V_STBY")
		)
		(pad "2" smd rect
			(at 0 0.889 180)
			(size 0.508 0.508)
			(layers "B.Cu" "B.Mask" "B.Paste")
			(net "A_HSC_PWGIN")
		)
		(zone
			(layer "B.Cu")
			(hatch none 0.5)
			(connect_pads
				(clearance 0)
			)
			(min_thickness 0.25)
			(keepout
				(tracks allowed)
				(vias not_allowed)
				(pads allowed)
				(copperpour not_allowed)
				(footprints allowed)
			)
			(placement
				(enabled no)
				(sheetname "")
			)
			(fill
				(thermal_gap 0.5)
				(thermal_bridge_width 0.5)
				(island_removal_mode 0)
			)
			(polygon
				(pts
					(xy 14.478 -75.8698) (xy 13.97 -75.8698) (xy 13.97 -75.4888) (xy 14.478 -75.4888)
				)
			)
		)
		(zone
			(layer "B.Cu")
			(hatch none 0.5)
			(connect_pads
				(clearance 0)
			)
			(min_thickness 0.25)
			(keepout
				(tracks not_allowed)
				(vias allowed)
				(pads allowed)
				(copperpour not_allowed)
				(footprints allowed)
			)
			(placement
				(enabled no)
				(sheetname "")
			)
			(fill
				(thermal_gap 0.5)
				(thermal_bridge_width 0.5)
				(island_removal_mode 0)
			)
			(polygon
				(pts
					(xy 14.478 -75.4888) (xy 13.97 -75.4888) (xy 13.97 -75.8698) (xy 14.478 -75.8698)
				)
			)
		)
	)
)
